(kicad_pcb
	(version 20260206)
	(generator "pcbnew")
	(generator_version "10.0")
	(general
		(thickness 1.6)
		(legacy_teardrops no)
	)
	(paper "A4")
	(title_block
		(title "01162023_DA0F0TEBIF0_F0T_Expander_BD_F_brd_V02_OCP.brd")
		(comment 1 "Grand Teton / footprints 6714-6720 of 9728")
	)
	(layers
		(0 "F.Cu" signal "TOP")
		(4 "In1.Cu" signal "GND")
		(6 "In2.Cu" signal "VCC")
		(8 "In3.Cu" signal "VCC1")
		(10 "In4.Cu" signal "GND1")
		(12 "In5.Cu" signal "IN1")
		(14 "In6.Cu" signal "GND2")
		(16 "In7.Cu" signal "IN2")
		(18 "In8.Cu" signal "GND3")
		(20 "In9.Cu" signal "IN3")
		(22 "In10.Cu" signal "GND4")
		(24 "In11.Cu" signal "IN4")
		(26 "In12.Cu" signal "GND5")
		(28 "In13.Cu" signal "IN5")
		(30 "In14.Cu" signal "GND6")
		(32 "In15.Cu" signal "IN6")
		(34 "In16.Cu" signal "GND7")
		(2 "B.Cu" signal "BOTTOM")
		(9 "F.Adhes" user "F.Adhesive")
		(11 "B.Adhes" user "B.Adhesive")
		(13 "F.Paste" user "Package Geometry/Pastemask Top")
		(15 "B.Paste" user "Package Geometry/Pastemask Bottom")
		(5 "F.SilkS" user "Ref Des/Silkscreen Top")
		(7 "B.SilkS" user "Ref Des/Silkscreen Bottom")
		(1 "F.Mask" user "Board Geometry/Soldermask Top")
		(3 "B.Mask" user "Board Geometry/Soldermask Bottom")
		(17 "Dwgs.User" user "User.Drawings")
		(19 "Cmts.User" user "User.Comments")
		(21 "Eco1.User" user "User.Eco1")
		(23 "Eco2.User" user "User.Eco2")
		(25 "Edge.Cuts" user "Board Geometry/Outline")
		(27 "Margin" user)
		(31 "F.CrtYd" user "Package Geometry/Place Bound Top")
		(29 "B.CrtYd" user "Package Geometry/Place Bound Bottom")
		(35 "F.Fab" user "Ref Des/Assembly Top")
		(33 "B.Fab" user "Ref Des/Assembly Bottom")
	)
	(footprint ""
		(layer "F.Cu")
		(at 200.691496 -113.41354)
		(property "Reference" "R184"
			(at 0 0 0)
			(layer "F.SilkS")
			(hide yes)
			(effects
				(font
					(size 1.27 1.27)
				)
			)
		)
		(property "Value" ""
			(at 0 0 0)
			(layer "F.Fab")
			(effects
				(font
					(size 1.27 1.27)
				)
			)
		)
		(duplicate_pad_numbers_are_jumpers no)
		(fp_line
			(start -0.7874 -0.4064)
			(end 0.7874 -0.4064)
			(stroke
				(width 0.1524)
				(type default)
			)
			(layer "F.SilkS")
		)
		(fp_line
			(start -0.7874 0.4064)
			(end -0.7874 -0.4064)
			(stroke
				(width 0.1524)
				(type default)
			)
			(layer "F.SilkS")
		)
		(fp_line
			(start 0.7874 -0.4064)
			(end 0.7874 0.4064)
			(stroke
				(width 0.1524)
				(type default)
			)
			(layer "F.SilkS")
		)
		(fp_line
			(start 0.7874 0.4064)
			(end -0.7874 0.4064)
			(stroke
				(width 0.1524)
				(type default)
			)
			(layer "F.SilkS")
		)
		(fp_line
			(start -0.67945 -0.305054)
			(end -0.12065 -0.305054)
			(stroke
				(width 0.1)
				(type default)
			)
			(layer "F.Fab")
		)
		(fp_line
			(start -0.67945 0.3048)
			(end -0.67945 -0.305054)
			(stroke
				(width 0.1)
				(type default)
			)
			(layer "F.Fab")
		)
		(fp_line
			(start -0.12065 -0.305054)
			(end -0.12065 -0.2794)
			(stroke
				(width 0.1)
				(type default)
			)
			(layer "F.Fab")
		)
		(fp_line
			(start -0.12065 -0.2794)
			(end 0.12065 -0.2794)
			(stroke
				(width 0.1)
				(type default)
			)
			(layer "F.Fab")
		)
		(fp_line
			(start -0.12065 0.2794)
			(end -0.12065 0.3048)
			(stroke
				(width 0.1)
				(type default)
			)
			(layer "F.Fab")
		)
		(fp_line
			(start -0.12065 0.3048)
			(end -0.67945 0.3048)
			(stroke
				(width 0.1)
				(type default)
			)
			(layer "F.Fab")
		)
		(fp_line
			(start 0.120396 0.2794)
			(end -0.12065 0.2794)
			(stroke
				(width 0.1)
				(type default)
			)
			(layer "F.Fab")
		)
		(fp_line
			(start 0.120396 0.3048)
			(end 0.120396 0.2794)
			(stroke
				(width 0.1)
				(type default)
			)
			(layer "F.Fab")
		)
		(fp_line
			(start 0.12065 -0.3048)
			(end 0.67945 -0.3048)
			(stroke
				(width 0.1)
				(type default)
			)
			(layer "F.Fab")
		)
		(fp_line
			(start 0.12065 -0.2794)
			(end 0.12065 -0.3048)
			(stroke
				(width 0.1)
				(type default)
			)
			(layer "F.Fab")
		)
		(fp_line
			(start 0.67945 -0.3048)
			(end 0.67945 0.3048)
			(stroke
				(width 0.1)
				(type default)
			)
			(layer "F.Fab")
		)
		(fp_line
			(start 0.67945 0.3048)
			(end 0.120396 0.3048)
			(stroke
				(width 0.1)
				(type default)
			)
			(layer "F.Fab")
		)
		(pad "1" smd circle
			(at -0.40005 0)
			(size 0 0)
			(layers "F.Cu" "F.Mask" "F.Paste")
			(net "NIC3_BIF1_N")
		)
		(pad "2" smd circle
			(at 0.40005 0)
			(size 0 0)
			(layers "F.Cu" "F.Mask" "F.Paste")
			(net "P3V3_AUX")
		)
	)
	(footprint ""
		(layer "F.Cu")
		(at 447.50609 -113.114582 -90)
		(property "Reference" "PD99"
			(at 3.945382 -2.22758 90)
			(unlocked yes)
			(layer "F.SilkS")
			(effects
				(font
					(size 0.7874 0.5842)
					(thickness 0.1524)
				)
				(justify left)
			)
		)
		(property "Value" ""
			(at 0 0 270)
			(layer "F.Fab")
			(effects
				(font
					(size 1.27 1.27)
				)
			)
		)
		(duplicate_pad_numbers_are_jumpers no)
		(fp_line
			(start -3.400044 1.459992)
			(end -3.400044 -1.459992)
			(stroke
				(width 0.1524)
				(type default)
			)
			(layer "F.SilkS")
		)
		(fp_line
			(start 4.107942 1.459992)
			(end -3.400044 1.459992)
			(stroke
				(width 0.1524)
				(type default)
			)
			(layer "F.SilkS")
		)
		(fp_line
			(start -3.400044 -1.459992)
			(end 4.107942 -1.459992)
			(stroke
				(width 0.1524)
				(type default)
			)
			(layer "F.SilkS")
		)
		(fp_line
			(start 4.107942 -1.459992)
			(end 4.107942 1.459992)
			(stroke
				(width 0.1524)
				(type default)
			)
			(layer "F.SilkS")
		)
		(fp_rect
			(start 4.107942 1.459992)
			(end 3.308096 -1.459992)
			(stroke
				(width 0)
				(type default)
			)
			(fill yes)
			(layer "F.SilkS")
		)
		(fp_line
			(start -2.29997 1.459992)
			(end -2.29997 -1.459992)
			(stroke
				(width 0.1)
				(type default)
			)
			(layer "F.Fab")
		)
		(fp_line
			(start 2.29997 1.459992)
			(end -2.29997 1.459992)
			(stroke
				(width 0.1)
				(type default)
			)
			(layer "F.Fab")
		)
		(fp_line
			(start -2.29997 -1.459992)
			(end 2.29997 -1.459992)
			(stroke
				(width 0.1)
				(type default)
			)
			(layer "F.Fab")
		)
		(fp_line
			(start 2.29997 -1.459992)
			(end 2.29997 1.459992)
			(stroke
				(width 0.1)
				(type default)
			)
			(layer "F.Fab")
		)
		(fp_text user "-"
			(at 3.36169 2.127504 90)
			(unlocked yes)
			(layer "F.SilkS")
			(effects
				(font
					(size 1.905 1.4224)
					(thickness 0.1524)
				)
				(justify left)
			)
		)
		(fp_text user "+"
			(at -4.7752 -0.12065 270)
			(unlocked yes)
			(layer "F.SilkS")
			(effects
				(font
					(size 1.905 1.4224)
					(thickness 0.1524)
				)
				(justify left)
			)
		)
		(fp_text user "-"
			(at 5.4102 0.29845 90)
			(unlocked yes)
			(layer "F.Fab")
			(effects
				(font
					(size 1.905 1.4224)
					(thickness 0.1524)
				)
				(justify left)
			)
		)
		(fp_text user "+"
			(at -4.7752 -0.12065 270)
			(unlocked yes)
			(layer "F.Fab")
			(effects
				(font
					(size 1.905 1.4224)
					(thickness 0.1524)
				)
				(justify left)
			)
		)
		(pad "A" smd rect
			(at -1.999996 0)
			(size 1.7018 2.5146)
			(layers "F.Cu" "F.Mask" "F.Paste")
			(net "GND")
		)
		(pad "C" smd rect
			(at 1.999996 0)
			(size 1.7018 2.5146)
			(layers "F.Cu" "F.Mask" "F.Paste")
			(net "P12V_NIC7_R")
		)
	)
	(footprint ""
		(layer "F.Cu")
		(at 126.210314 -122.931428 180)
		(property "Reference" "PC457"
			(at 0 0 180)
			(layer "F.SilkS")
			(hide yes)
			(effects
				(font
					(size 1.27 1.27)
				)
			)
		)
		(property "Value" ""
			(at 0 0 180)
			(layer "F.Fab")
			(effects
				(font
					(size 1.27 1.27)
				)
			)
		)
		(duplicate_pad_numbers_are_jumpers no)
		(fp_line
			(start 0.7874 0.4064)
			(end -0.7874 0.4064)
			(stroke
				(width 0.1524)
				(type default)
			)
			(layer "F.SilkS")
		)
		(fp_line
			(start 0.7874 -0.4064)
			(end 0.7874 0.4064)
			(stroke
				(width 0.1524)
				(type default)
			)
			(layer "F.SilkS")
		)
		(fp_line
			(start -0.7874 0.4064)
			(end -0.7874 -0.4064)
			(stroke
				(width 0.1524)
				(type default)
			)
			(layer "F.SilkS")
		)
		(fp_line
			(start -0.7874 -0.4064)
			(end 0.7874 -0.4064)
			(stroke
				(width 0.1524)
				(type default)
			)
			(layer "F.SilkS")
		)
		(fp_line
			(start 0.67945 0.3048)
			(end 0.120396 0.3048)
			(stroke
				(width 0.1)
				(type default)
			)
			(layer "F.Fab")
		)
		(fp_line
			(start 0.67945 -0.3048)
			(end 0.67945 0.3048)
			(stroke
				(width 0.1)
				(type default)
			)
			(layer "F.Fab")
		)
		(fp_line
			(start 0.12065 -0.2794)
			(end 0.12065 -0.3048)
			(stroke
				(width 0.1)
				(type default)
			)
			(layer "F.Fab")
		)
		(fp_line
			(start 0.12065 -0.3048)
			(end 0.67945 -0.3048)
			(stroke
				(width 0.1)
				(type default)
			)
			(layer "F.Fab")
		)
		(fp_line
			(start 0.120396 0.3048)
			(end 0.120396 0.2794)
			(stroke
				(width 0.1)
				(type default)
			)
			(layer "F.Fab")
		)
		(fp_line
			(start 0.120396 0.2794)
			(end -0.12065 0.2794)
			(stroke
				(width 0.1)
				(type default)
			)
			(layer "F.Fab")
		)
		(fp_line
			(start -0.12065 0.3048)
			(end -0.67945 0.3048)
			(stroke
				(width 0.1)
				(type default)
			)
			(layer "F.Fab")
		)
		(fp_line
			(start -0.12065 0.2794)
			(end -0.12065 0.3048)
			(stroke
				(width 0.1)
				(type default)
			)
			(layer "F.Fab")
		)
		(fp_line
			(start -0.12065 -0.2794)
			(end 0.12065 -0.2794)
			(stroke
				(width 0.1)
				(type default)
			)
			(layer "F.Fab")
		)
		(fp_line
			(start -0.12065 -0.305054)
			(end -0.12065 -0.2794)
			(stroke
				(width 0.1)
				(type default)
			)
			(layer "F.Fab")
		)
		(fp_line
			(start -0.67945 0.3048)
			(end -0.67945 -0.305054)
			(stroke
				(width 0.1)
				(type default)
			)
			(layer "F.Fab")
		)
		(fp_line
			(start -0.67945 -0.305054)
			(end -0.12065 -0.305054)
			(stroke
				(width 0.1)
				(type default)
			)
			(layer "F.Fab")
		)
		(pad "1" smd circle
			(at -0.40005 0 180)
			(size 0 0)
			(layers "F.Cu" "F.Mask" "F.Paste")
			(net "P5V_AUX")
		)
		(pad "2" smd circle
			(at 0.40005 0 180)
			(size 0 0)
			(layers "F.Cu" "F.Mask" "F.Paste")
			(net "GND")
		)
	)
	(footprint ""
		(layer "F.Cu")
		(at 366.955578 -87.213694 180)
		(property "Reference" "R1626"
			(at 0 0 180)
			(layer "F.SilkS")
			(hide yes)
			(effects
				(font
					(size 1.27 1.27)
				)
			)
		)
		(property "Value" ""
			(at 0 0 180)
			(layer "F.Fab")
			(effects
				(font
					(size 1.27 1.27)
				)
			)
		)
		(duplicate_pad_numbers_are_jumpers no)
		(fp_line
			(start 0.7874 0.4064)
			(end -0.7874 0.4064)
			(stroke
				(width 0.1524)
				(type default)
			)
			(layer "F.SilkS")
		)
		(fp_line
			(start 0.7874 -0.4064)
			(end 0.7874 0.4064)
			(stroke
				(width 0.1524)
				(type default)
			)
			(layer "F.SilkS")
		)
		(fp_line
			(start -0.7874 0.4064)
			(end -0.7874 -0.4064)
			(stroke
				(width 0.1524)
				(type default)
			)
			(layer "F.SilkS")
		)
		(fp_line
			(start -0.7874 -0.4064)
			(end 0.7874 -0.4064)
			(stroke
				(width 0.1524)
				(type default)
			)
			(layer "F.SilkS")
		)
		(fp_line
			(start 0.67945 0.3048)
			(end 0.120396 0.3048)
			(stroke
				(width 0.1)
				(type default)
			)
			(layer "F.Fab")
		)
		(fp_line
			(start 0.67945 -0.3048)
			(end 0.67945 0.3048)
			(stroke
				(width 0.1)
				(type default)
			)
			(layer "F.Fab")
		)
		(fp_line
			(start 0.12065 -0.2794)
			(end 0.12065 -0.3048)
			(stroke
				(width 0.1)
				(type default)
			)
			(layer "F.Fab")
		)
		(fp_line
			(start 0.12065 -0.3048)
			(end 0.67945 -0.3048)
			(stroke
				(width 0.1)
				(type default)
			)
			(layer "F.Fab")
		)
		(fp_line
			(start 0.120396 0.3048)
			(end 0.120396 0.2794)
			(stroke
				(width 0.1)
				(type default)
			)
			(layer "F.Fab")
		)
		(fp_line
			(start 0.120396 0.2794)
			(end -0.12065 0.2794)
			(stroke
				(width 0.1)
				(type default)
			)
			(layer "F.Fab")
		)
		(fp_line
			(start -0.12065 0.3048)
			(end -0.67945 0.3048)
			(stroke
				(width 0.1)
				(type default)
			)
			(layer "F.Fab")
		)
		(fp_line
			(start -0.12065 0.2794)
			(end -0.12065 0.3048)
			(stroke
				(width 0.1)
				(type default)
			)
			(layer "F.Fab")
		)
		(fp_line
			(start -0.12065 -0.2794)
			(end 0.12065 -0.2794)
			(stroke
				(width 0.1)
				(type default)
			)
			(layer "F.Fab")
		)
		(fp_line
			(start -0.12065 -0.305054)
			(end -0.12065 -0.2794)
			(stroke
				(width 0.1)
				(type default)
			)
			(layer "F.Fab")
		)
		(fp_line
			(start -0.67945 0.3048)
			(end -0.67945 -0.305054)
			(stroke
				(width 0.1)
				(type default)
			)
			(layer "F.Fab")
		)
		(fp_line
			(start -0.67945 -0.305054)
			(end -0.12065 -0.305054)
			(stroke
				(width 0.1)
				(type default)
			)
			(layer "F.Fab")
		)
		(pad "1" smd circle
			(at -0.40005 0 180)
			(size 0 0)
			(layers "F.Cu" "F.Mask" "F.Paste")
			(net "SMB_BIC_I2C9_MUX1_SSD14_R_SCL")
		)
		(pad "2" smd circle
			(at 0.40005 0 180)
			(size 0 0)
			(layers "F.Cu" "F.Mask" "F.Paste")
			(net "SMB_BIC_I2C9_MUX1_SSD14_SCL")
		)
	)
	(footprint ""
		(layer "F.Cu")
		(at 438.233058 -311.946544 135)
		(property "Reference" "R1438"
			(at 0 0 135)
			(layer "F.SilkS")
			(hide yes)
			(effects
				(font
					(size 1.27 1.27)
				)
			)
		)
		(property "Value" ""
			(at 0 0 135)
			(layer "F.Fab")
			(effects
				(font
					(size 1.27 1.27)
				)
			)
		)
		(duplicate_pad_numbers_are_jumpers no)
		(fp_line
			(start 0.787389 -0.406267)
			(end 0.787389 0.406267)
			(stroke
				(width 0.1524)
				(type default)
			)
			(layer "F.SilkS")
		)
		(fp_line
			(start 0.787389 0.406267)
			(end -0.787389 0.406267)
			(stroke
				(width 0.1524)
				(type default)
			)
			(layer "F.SilkS")
		)
		(fp_line
			(start -0.787389 -0.406267)
			(end 0.787389 -0.406267)
			(stroke
				(width 0.1524)
				(type default)
			)
			(layer "F.SilkS")
		)
		(fp_line
			(start -0.787389 0.406267)
			(end -0.787389 -0.406267)
			(stroke
				(width 0.1524)
				(type default)
			)
			(layer "F.SilkS")
		)
		(fp_line
			(start 0.679446 -0.30479)
			(end 0.679446 0.30479)
			(stroke
				(width 0.1)
				(type default)
			)
			(layer "F.Fab")
		)
		(fp_line
			(start 0.120515 -0.30479)
			(end 0.679446 -0.30479)
			(stroke
				(width 0.1)
				(type default)
			)
			(layer "F.Fab")
		)
		(fp_line
			(start 0.120695 -0.279466)
			(end 0.120515 -0.30479)
			(stroke
				(width 0.1)
				(type default)
			)
			(layer "F.Fab")
		)
		(fp_line
			(start 0.679446 0.30479)
			(end 0.120515 0.30479)
			(stroke
				(width 0.1)
				(type default)
			)
			(layer "F.Fab")
		)
		(fp_line
			(start -0.120695 -0.304969)
			(end -0.120695 -0.279466)
			(stroke
				(width 0.1)
				(type default)
			)
			(layer "F.Fab")
		)
		(fp_line
			(start -0.120695 -0.279466)
			(end 0.120695 -0.279466)
			(stroke
				(width 0.1)
				(type default)
			)
			(layer "F.Fab")
		)
		(fp_line
			(start 0.120335 0.279466)
			(end -0.120695 0.279466)
			(stroke
				(width 0.1)
				(type default)
			)
			(layer "F.Fab")
		)
		(fp_line
			(start 0.120515 0.30479)
			(end 0.120335 0.279466)
			(stroke
				(width 0.1)
				(type default)
			)
			(layer "F.Fab")
		)
		(fp_line
			(start -0.679446 -0.305149)
			(end -0.120695 -0.304969)
			(stroke
				(width 0.1)
				(type default)
			)
			(layer "F.Fab")
		)
		(fp_line
			(start -0.120695 0.279466)
			(end -0.120515 0.30479)
			(stroke
				(width 0.1)
				(type default)
			)
			(layer "F.Fab")
		)
		(fp_line
			(start -0.120515 0.30479)
			(end -0.679446 0.30479)
			(stroke
				(width 0.1)
				(type default)
			)
			(layer "F.Fab")
		)
		(fp_line
			(start -0.679446 0.30479)
			(end -0.679446 -0.305149)
			(stroke
				(width 0.1)
				(type default)
			)
			(layer "F.Fab")
		)
		(pad "1" smd circle
			(at -0.40005 0 135)
			(size 0 0)
			(layers "F.Cu" "F.Mask" "F.Paste")
			(net "PEX3_SPARE5")
		)
		(pad "2" smd circle
			(at 0.40005 0 135)
			(size 0 0)
			(layers "F.Cu" "F.Mask" "F.Paste")
			(net "P1V8_PEX")
		)
	)
	(footprint ""
		(layer "F.Cu")
		(at 233.933746 -120.381268 -90)
		(property "Reference" "R947"
			(at 0 0 270)
			(layer "F.SilkS")
			(hide yes)
			(effects
				(font
					(size 1.27 1.27)
				)
			)
		)
		(property "Value" ""
			(at 0 0 270)
			(layer "F.Fab")
			(effects
				(font
					(size 1.27 1.27)
				)
			)
		)
		(duplicate_pad_numbers_are_jumpers no)
		(fp_line
			(start -0.7874 0.4064)
			(end -0.7874 -0.4064)
			(stroke
				(width 0.1524)
				(type default)
			)
			(layer "F.SilkS")
		)
		(fp_line
			(start 0.7874 0.4064)
			(end -0.7874 0.4064)
			(stroke
				(width 0.1524)
				(type default)
			)
			(layer "F.SilkS")
		)
		(fp_line
			(start -0.7874 -0.4064)
			(end 0.7874 -0.4064)
			(stroke
				(width 0.1524)
				(type default)
			)
			(layer "F.SilkS")
		)
		(fp_line
			(start 0.7874 -0.4064)
			(end 0.7874 0.4064)
			(stroke
				(width 0.1524)
				(type default)
			)
			(layer "F.SilkS")
		)
		(fp_line
			(start -0.67945 0.3048)
			(end -0.67945 -0.305054)
			(stroke
				(width 0.1)
				(type default)
			)
			(layer "F.Fab")
		)
		(fp_line
			(start -0.12065 0.3048)
			(end -0.67945 0.3048)
			(stroke
				(width 0.1)
				(type default)
			)
			(layer "F.Fab")
		)
		(fp_line
			(start 0.120396 0.3048)
			(end 0.120396 0.2794)
			(stroke
				(width 0.1)
				(type default)
			)
			(layer "F.Fab")
		)
		(fp_line
			(start 0.67945 0.3048)
			(end 0.120396 0.3048)
			(stroke
				(width 0.1)
				(type default)
			)
			(layer "F.Fab")
		)
		(fp_line
			(start -0.12065 0.2794)
			(end -0.12065 0.3048)
			(stroke
				(width 0.1)
				(type default)
			)
			(layer "F.Fab")
		)
		(fp_line
			(start 0.120396 0.2794)
			(end -0.12065 0.2794)
			(stroke
				(width 0.1)
				(type default)
			)
			(layer "F.Fab")
		)
		(fp_line
			(start -0.12065 -0.2794)
			(end 0.12065 -0.2794)
			(stroke
				(width 0.1)
				(type default)
			)
			(layer "F.Fab")
		)
		(fp_line
			(start 0.12065 -0.2794)
			(end 0.12065 -0.3048)
			(stroke
				(width 0.1)
				(type default)
			)
			(layer "F.Fab")
		)
		(fp_line
			(start 0.12065 -0.3048)
			(end 0.67945 -0.3048)
			(stroke
				(width 0.1)
				(type default)
			)
			(layer "F.Fab")
		)
		(fp_line
			(start 0.67945 -0.3048)
			(end 0.67945 0.3048)
			(stroke
				(width 0.1)
				(type default)
			)
			(layer "F.Fab")
		)
		(fp_line
			(start -0.67945 -0.305054)
			(end -0.12065 -0.305054)
			(stroke
				(width 0.1)
				(type default)
			)
			(layer "F.Fab")
		)
		(fp_line
			(start -0.12065 -0.305054)
			(end -0.12065 -0.2794)
			(stroke
				(width 0.1)
				(type default)
			)
			(layer "F.Fab")
		)
		(pad "1" smd circle
			(at -0.40005 0 270)
			(size 0 0)
			(layers "F.Cu" "F.Mask" "F.Paste")
			(net "P3V3_AUX")
		)
		(pad "2" smd circle
			(at 0.40005 0 270)
			(size 0 0)
			(layers "F.Cu" "F.Mask" "F.Paste")
			(net "PWRGD_P12V_NIC3_CO")
		)
	)
	(footprint ""
		(layer "F.Cu")
		(at 469.310212 -555.019972 180)
		(property "Reference" "SCREW_SSD11_2"
			(at -5.6007 -1.402334 0)
			(unlocked yes)
			(layer "B.SilkS")
			(effects
				(font
					(size 0.7874 0.5842)
					(thickness 0.1524)
				)
				(justify mirror)
			)
		)
		(property "Value" ""
			(at 0 0 180)
			(layer "F.Fab")
			(effects
				(font
					(size 1.27 1.27)
				)
			)
		)
		(duplicate_pad_numbers_are_jumpers no)
		(pad "1" thru_hole circle
			(at 0 0 180)
			(size 0.4572 0.4572)
			(drill 0.2032)
			(layers "*.Cu" "*.Mask")
			(remove_unused_layers no)
			(net "Net_9151")
			(clearance 0.127)
			(thermal_gap 0.127)
			(padstack
				(mode front_inner_back)
				(layer "Inner"
					(shape circle)
					(size 0.4572 0.4572)
					(clearance 0.127)
				)
				(layer "B.Cu"
					(shape circle)
					(size 0.508 0.508)
					(clearance 0.1016)
				)
			)
		)
	)
)
